(kicad_pcb
	(version 20260206)
	(generator "pcbnew")
	(generator_version "10.0")
	(general
		(thickness 1.6)
		(legacy_teardrops no)
	)
	(paper "A4")
	(title_block
		(title "panther-plus-userver — 13130-1b_20150205.brd")
		(comment 1 "Honey Badger (Wiwynn) / footprint 1214 of 1509 (DIMM3), pads 177-183 of 210")
	)
	(layers
		(0 "F.Cu" signal "TOP")
		(4 "In1.Cu" signal "L2")
		(6 "In2.Cu" signal "L3")
		(8 "In3.Cu" signal "L4")
		(10 "In4.Cu" signal "L5")
		(12 "In5.Cu" signal "L6")
		(14 "In6.Cu" signal "L7")
		(16 "In7.Cu" signal "L8")
		(18 "In8.Cu" signal "L9")
		(20 "In9.Cu" signal "L10")
		(22 "In10.Cu" signal "L11")
		(2 "B.Cu" signal "BOTTOM")
		(9 "F.Adhes" user "F.Adhesive")
		(11 "B.Adhes" user "B.Adhesive")
		(13 "F.Paste" user "Package Geometry/Pastemask Top")
		(15 "B.Paste" user "Package Geometry/Pastemask Bottom")
		(5 "F.SilkS" user "Ref Des/Silkscreen Top")
		(7 "B.SilkS" user "Ref Des/Silkscreen Bottom")
		(1 "F.Mask" user "Board Geometry/Soldermask Top")
		(3 "B.Mask" user "Board Geometry/Soldermask Bottom")
		(17 "Dwgs.User" user "User.Drawings")
		(19 "Cmts.User" user "User.Comments")
		(21 "Eco1.User" user "User.Eco1")
		(23 "Eco2.User" user "User.Eco2")
		(25 "Edge.Cuts" user "Board Geometry/Outline")
		(27 "Margin" user)
		(31 "F.CrtYd" user "Package Geometry/Place Bound Top")
		(29 "B.CrtYd" user "Package Geometry/Place Bound Bottom")
		(35 "F.Fab" user "Ref Des/Assembly Top")
		(33 "B.Fab" user "Ref Des/Assembly Bottom")
	)
	(footprint ""
		(layer "B.Cu")
		(at 159.999934 -5.790692)
		(property "Reference" "DIMM3"
			(at 0 0 0)
			(layer "B.SilkS")
			(hide yes)
			(effects
				(font
					(size 1.27 1.27)
				)
				(justify mirror)
			)
		)
		(property "Value" "DDR3-204P-142-COLAY-1-GP-U"
			(at 41.312338 -16.676878 0)
			(unlocked yes)
			(layer "B.Fab")
			(hide yes)
			(effects
				(font
					(size 1.016 1.016)
					(thickness 0.1524)
				)
				(justify mirror)
			)
		)
		(property "Device Type" "AS0A626-J8R6-7H-COLAY-1"
			(at 41.312338 -18.200878 0)
			(unlocked yes)
			(layer "B.Fab")
			(hide yes)
			(effects
				(font
					(size 1.016 1.016)
					(thickness 0.1524)
				)
				(justify mirror)
			)
		)
		(duplicate_pad_numbers_are_jumpers no)
		(pad "175" smd custom
			(at 22.949916 -4.100068 180)
			(size 0.1143 0.1143)
			(layers "B.Cu" "B.Mask" "B.Paste")
			(net "GND")
			(options
				(clearance outline)
				(anchor circle)
			)
			(primitives
				(gr_poly
					(pts
						(xy 0 -0.9017) (xy -0.03175 -0.89916) (xy -0.0635 -0.889) (xy -0.09144 -0.87376) (xy -0.11684 -0.85344)
						(xy -0.13716 -0.82804) (xy -0.1524 -0.8001) (xy -0.16256 -0.76835) (xy -0.1651 -0.7366) (xy -0.1651 -0.19685)
						(xy -0.17272 -0.18923) (xy -0.17907 -0.18034) (xy -0.18669 -0.17145) (xy -0.19177 -0.16256) (xy -0.19812 -0.15367)
						(xy -0.20828 -0.13335) (xy -0.21971 -0.10287) (xy -0.22225 -0.09271) (xy -0.22479 -0.08128) (xy -0.22606 -0.07112)
						(xy -0.2286 -0.05969) (xy -0.2286 -0.01651) (xy -0.22606 -0.00508) (xy -0.22479 0.00508) (xy -0.22225 0.01651)
						(xy -0.21971 0.02667) (xy -0.20828 0.05715) (xy -0.19812 0.07747) (xy -0.19177 0.08636) (xy -0.18669 0.09525)
						(xy -0.17907 0.10414) (xy -0.17272 0.11303) (xy -0.1651 0.12065) (xy -0.1651 0.7366) (xy -0.16256 0.76835)
						(xy -0.1524 0.8001) (xy -0.13716 0.82804) (xy -0.11684 0.85344) (xy -0.09144 0.87376) (xy -0.0635 0.889)
						(xy -0.03175 0.89916) (xy 0 0.9017) (xy 0.03175 0.89916) (xy 0.0635 0.889) (xy 0.09144 0.87376)
						(xy 0.11684 0.85344) (xy 0.13716 0.82804) (xy 0.1524 0.8001) (xy 0.16256 0.76835) (xy 0.1651 0.7366)
						(xy 0.1651 0.11938) (xy 0.17272 0.11176) (xy 0.19812 0.0762) (xy 0.2032 0.06604) (xy 0.20701 0.05715)
						(xy 0.21209 0.04699) (xy 0.2159 0.03683) (xy 0.21844 0.02667) (xy 0.22225 0.01524) (xy 0.22352 0.00508)
						(xy 0.22606 -0.00508) (xy 0.22733 -0.01651) (xy 0.22733 -0.02667) (xy 0.2286 -0.0381) (xy 0.22733 -0.04953)
						(xy 0.22733 -0.05969) (xy 0.22606 -0.07112) (xy 0.22352 -0.08128) (xy 0.22225 -0.09144) (xy 0.21844 -0.10287)
						(xy 0.2159 -0.11303) (xy 0.21209 -0.12319) (xy 0.20701 -0.13335) (xy 0.2032 -0.14224) (xy 0.19812 -0.1524)
						(xy 0.17272 -0.18796) (xy 0.1651 -0.19558) (xy 0.1651 -0.7366) (xy 0.16256 -0.76835) (xy 0.1524 -0.8001)
						(xy 0.13716 -0.82804) (xy 0.11684 -0.85344) (xy 0.09144 -0.87376) (xy 0.0635 -0.889) (xy 0.03175 -0.89916)
					)
					(width 0)
					(fill yes)
				)
			)
		)
		(pad "176" smd custom
			(at 23.24989 4.100068 180)
			(size 0.1143 0.1143)
			(layers "B.Cu" "B.Mask" "B.Paste")
			(net "M_B_DQ55")
			(options
				(clearance outline)
				(anchor circle)
			)
			(primitives
				(gr_poly
					(pts
						(xy 0 -0.9017) (xy -0.03175 -0.89916) (xy -0.0635 -0.889) (xy -0.09144 -0.87376) (xy -0.11684 -0.85344)
						(xy -0.13716 -0.82804) (xy -0.1524 -0.8001) (xy -0.16256 -0.76835) (xy -0.1651 -0.7366) (xy -0.1651 -0.11938)
						(xy -0.17272 -0.11176) (xy -0.19812 -0.0762) (xy -0.2032 -0.06604) (xy -0.20701 -0.05715) (xy -0.21209 -0.04699)
						(xy -0.2159 -0.03683) (xy -0.21844 -0.02667) (xy -0.22225 -0.01524) (xy -0.22352 -0.00508) (xy -0.22606 0.00508)
						(xy -0.22733 0.01651) (xy -0.22733 0.02667) (xy -0.2286 0.0381) (xy -0.22733 0.04953) (xy -0.22733 0.05969)
						(xy -0.22606 0.07112) (xy -0.22352 0.08128) (xy -0.22225 0.09144) (xy -0.21844 0.10287) (xy -0.2159 0.11303)
						(xy -0.21209 0.12319) (xy -0.20701 0.13335) (xy -0.2032 0.14224) (xy -0.19812 0.1524) (xy -0.17272 0.18796)
						(xy -0.1651 0.19558) (xy -0.1651 0.7366) (xy -0.16256 0.76835) (xy -0.1524 0.8001) (xy -0.13716 0.82804)
						(xy -0.11684 0.85344) (xy -0.09144 0.87376) (xy -0.0635 0.889) (xy -0.03175 0.89916) (xy 0 0.9017)
						(xy 0.03175 0.89916) (xy 0.0635 0.889) (xy 0.09144 0.87376) (xy 0.11684 0.85344) (xy 0.13716 0.82804)
						(xy 0.1524 0.8001) (xy 0.16256 0.76835) (xy 0.1651 0.7366) (xy 0.1651 0.19685) (xy 0.17272 0.18923)
						(xy 0.17907 0.18034) (xy 0.18669 0.17145) (xy 0.19177 0.16256) (xy 0.19812 0.15367) (xy 0.20828 0.13335)
						(xy 0.21971 0.10287) (xy 0.22225 0.09271) (xy 0.22479 0.08128) (xy 0.22606 0.07112) (xy 0.2286 0.05969)
						(xy 0.2286 0.01651) (xy 0.22606 0.00508) (xy 0.22479 -0.00508) (xy 0.22225 -0.01651) (xy 0.21971 -0.02667)
						(xy 0.20828 -0.05715) (xy 0.19812 -0.07747) (xy 0.19177 -0.08636) (xy 0.18669 -0.09525) (xy 0.17907 -0.10414)
						(xy 0.17272 -0.11303) (xy 0.1651 -0.12065) (xy 0.1651 -0.7366) (xy 0.16256 -0.76835) (xy 0.1524 -0.8001)
						(xy 0.13716 -0.82804) (xy 0.11684 -0.85344) (xy 0.09144 -0.87376) (xy 0.0635 -0.889) (xy 0.03175 -0.89916)
					)
					(width 0)
					(fill yes)
				)
			)
		)
		(pad "177" smd custom
			(at 23.550118 -4.100068 180)
			(size 0.1143 0.1143)
			(layers "B.Cu" "B.Mask" "B.Paste")
			(net "M_B_DQ50")
			(options
				(clearance outline)
				(anchor circle)
			)
			(primitives
				(gr_poly
					(pts
						(xy 0 -0.9017) (xy -0.03175 -0.89916) (xy -0.0635 -0.889) (xy -0.09144 -0.87376) (xy -0.11684 -0.85344)
						(xy -0.13716 -0.82804) (xy -0.1524 -0.8001) (xy -0.16256 -0.76835) (xy -0.1651 -0.7366) (xy -0.1651 -0.44958)
						(xy -0.17272 -0.44196) (xy -0.19812 -0.4064) (xy -0.2032 -0.39624) (xy -0.20701 -0.38735) (xy -0.21209 -0.37719)
						(xy -0.2159 -0.36703) (xy -0.21844 -0.35687) (xy -0.22225 -0.34544) (xy -0.22352 -0.33528) (xy -0.22606 -0.32512)
						(xy -0.22733 -0.31369) (xy -0.22733 -0.30353) (xy -0.2286 -0.2921) (xy -0.22733 -0.28067) (xy -0.22733 -0.27051)
						(xy -0.22606 -0.25908) (xy -0.22352 -0.24892) (xy -0.22225 -0.23876) (xy -0.21844 -0.22733) (xy -0.2159 -0.21717)
						(xy -0.21209 -0.20701) (xy -0.20701 -0.19685) (xy -0.2032 -0.18796) (xy -0.19812 -0.1778) (xy -0.17272 -0.14224)
						(xy -0.1651 -0.13462) (xy -0.1651 0.7366) (xy -0.16256 0.76835) (xy -0.1524 0.8001) (xy -0.13716 0.82804)
						(xy -0.11684 0.85344) (xy -0.09144 0.87376) (xy -0.0635 0.889) (xy -0.03175 0.89916) (xy 0 0.9017)
						(xy 0.03175 0.89916) (xy 0.0635 0.889) (xy 0.09144 0.87376) (xy 0.11684 0.85344) (xy 0.13716 0.82804)
						(xy 0.1524 0.8001) (xy 0.16256 0.76835) (xy 0.1651 0.7366) (xy 0.1651 -0.13462) (xy 0.17272 -0.14224)
						(xy 0.19812 -0.1778) (xy 0.2032 -0.18796) (xy 0.20701 -0.19685) (xy 0.21209 -0.20701) (xy 0.2159 -0.21717)
						(xy 0.21844 -0.22733) (xy 0.22225 -0.23876) (xy 0.22352 -0.24892) (xy 0.22606 -0.25908) (xy 0.22733 -0.27051)
						(xy 0.22733 -0.28067) (xy 0.2286 -0.2921) (xy 0.22733 -0.30353) (xy 0.22733 -0.31369) (xy 0.22606 -0.32512)
						(xy 0.22352 -0.33528) (xy 0.22225 -0.34544) (xy 0.21844 -0.35687) (xy 0.2159 -0.36703) (xy 0.21209 -0.37719)
						(xy 0.20701 -0.38735) (xy 0.2032 -0.39624) (xy 0.19812 -0.4064) (xy 0.17272 -0.44196) (xy 0.1651 -0.44958)
						(xy 0.1651 -0.7366) (xy 0.16256 -0.76835) (xy 0.1524 -0.8001) (xy 0.13716 -0.82804) (xy 0.11684 -0.85344)
						(xy 0.09144 -0.87376) (xy 0.0635 -0.889) (xy 0.03175 -0.89916)
					)
					(width 0)
					(fill yes)
				)
			)
		)
		(pad "178" smd custom
			(at 23.850092 4.100068 180)
			(size 0.1143 0.1143)
			(layers "B.Cu" "B.Mask" "B.Paste")
			(net "GND")
			(options
				(clearance outline)
				(anchor circle)
			)
			(primitives
				(gr_poly
					(pts
						(xy 0 -0.9017) (xy -0.03175 -0.89916) (xy -0.0635 -0.889) (xy -0.09144 -0.87376) (xy -0.11684 -0.85344)
						(xy -0.13716 -0.82804) (xy -0.1524 -0.8001) (xy -0.16256 -0.76835) (xy -0.1651 -0.7366) (xy -0.1651 0.13462)
						(xy -0.17272 0.14224) (xy -0.19812 0.1778) (xy -0.2032 0.18796) (xy -0.20701 0.19685) (xy -0.21209 0.20701)
						(xy -0.2159 0.21717) (xy -0.21844 0.22733) (xy -0.22225 0.23876) (xy -0.22352 0.24892) (xy -0.22606 0.25908)
						(xy -0.22733 0.27051) (xy -0.22733 0.28067) (xy -0.2286 0.2921) (xy -0.22733 0.30353) (xy -0.22733 0.31369)
						(xy -0.22606 0.32512) (xy -0.22352 0.33528) (xy -0.22225 0.34544) (xy -0.21844 0.35687) (xy -0.2159 0.36703)
						(xy -0.21209 0.37719) (xy -0.20701 0.38735) (xy -0.2032 0.39624) (xy -0.19812 0.4064) (xy -0.17272 0.44196)
						(xy -0.1651 0.44958) (xy -0.1651 0.7366) (xy -0.16256 0.76835) (xy -0.1524 0.8001) (xy -0.13716 0.82804)
						(xy -0.11684 0.85344) (xy -0.09144 0.87376) (xy -0.0635 0.889) (xy -0.03175 0.89916) (xy 0 0.9017)
						(xy 0.03175 0.89916) (xy 0.0635 0.889) (xy 0.09144 0.87376) (xy 0.11684 0.85344) (xy 0.13716 0.82804)
						(xy 0.1524 0.8001) (xy 0.16256 0.76835) (xy 0.1651 0.7366) (xy 0.1651 0.44958) (xy 0.17272 0.44196)
						(xy 0.19812 0.4064) (xy 0.2032 0.39624) (xy 0.20701 0.38735) (xy 0.21209 0.37719) (xy 0.2159 0.36703)
						(xy 0.21844 0.35687) (xy 0.22225 0.34544) (xy 0.22352 0.33528) (xy 0.22606 0.32512) (xy 0.22733 0.31369)
						(xy 0.22733 0.30353) (xy 0.2286 0.2921) (xy 0.22733 0.28067) (xy 0.22733 0.27051) (xy 0.22606 0.25908)
						(xy 0.22352 0.24892) (xy 0.22225 0.23876) (xy 0.21844 0.22733) (xy 0.2159 0.21717) (xy 0.21209 0.20701)
						(xy 0.20701 0.19685) (xy 0.2032 0.18796) (xy 0.19812 0.1778) (xy 0.17272 0.14224) (xy 0.1651 0.13462)
						(xy 0.1651 -0.7366) (xy 0.16256 -0.76835) (xy 0.1524 -0.8001) (xy 0.13716 -0.82804) (xy 0.11684 -0.85344)
						(xy 0.09144 -0.87376) (xy 0.0635 -0.889) (xy 0.03175 -0.89916)
					)
					(width 0)
					(fill yes)
				)
			)
		)
		(pad "179" smd custom
			(at 24.150066 -4.100068 180)
			(size 0.1143 0.1143)
			(layers "B.Cu" "B.Mask" "B.Paste")
			(net "M_B_DQ51")
			(options
				(clearance outline)
				(anchor circle)
			)
			(primitives
				(gr_poly
					(pts
						(xy 0 -0.9017) (xy -0.03175 -0.89916) (xy -0.0635 -0.889) (xy -0.09144 -0.87376) (xy -0.11684 -0.85344)
						(xy -0.13716 -0.82804) (xy -0.1524 -0.8001) (xy -0.16256 -0.76835) (xy -0.1651 -0.7366) (xy -0.1651 -0.19685)
						(xy -0.17272 -0.18923) (xy -0.17907 -0.18034) (xy -0.18669 -0.17145) (xy -0.19177 -0.16256) (xy -0.19812 -0.15367)
						(xy -0.20828 -0.13335) (xy -0.21971 -0.10287) (xy -0.22225 -0.09271) (xy -0.22479 -0.08128) (xy -0.22606 -0.07112)
						(xy -0.2286 -0.05969) (xy -0.2286 -0.01651) (xy -0.22606 -0.00508) (xy -0.22479 0.00508) (xy -0.22225 0.01651)
						(xy -0.21971 0.02667) (xy -0.20828 0.05715) (xy -0.19812 0.07747) (xy -0.19177 0.08636) (xy -0.18669 0.09525)
						(xy -0.17907 0.10414) (xy -0.17272 0.11303) (xy -0.1651 0.12065) (xy -0.1651 0.7366) (xy -0.16256 0.76835)
						(xy -0.1524 0.8001) (xy -0.13716 0.82804) (xy -0.11684 0.85344) (xy -0.09144 0.87376) (xy -0.0635 0.889)
						(xy -0.03175 0.89916) (xy 0 0.9017) (xy 0.03175 0.89916) (xy 0.0635 0.889) (xy 0.09144 0.87376)
						(xy 0.11684 0.85344) (xy 0.13716 0.82804) (xy 0.1524 0.8001) (xy 0.16256 0.76835) (xy 0.1651 0.7366)
						(xy 0.1651 0.11938) (xy 0.17272 0.11176) (xy 0.19812 0.0762) (xy 0.2032 0.06604) (xy 0.20701 0.05715)
						(xy 0.21209 0.04699) (xy 0.2159 0.03683) (xy 0.21844 0.02667) (xy 0.22225 0.01524) (xy 0.22352 0.00508)
						(xy 0.22606 -0.00508) (xy 0.22733 -0.01651) (xy 0.22733 -0.02667) (xy 0.2286 -0.0381) (xy 0.22733 -0.04953)
						(xy 0.22733 -0.05969) (xy 0.22606 -0.07112) (xy 0.22352 -0.08128) (xy 0.22225 -0.09144) (xy 0.21844 -0.10287)
						(xy 0.2159 -0.11303) (xy 0.21209 -0.12319) (xy 0.20701 -0.13335) (xy 0.2032 -0.14224) (xy 0.19812 -0.1524)
						(xy 0.17272 -0.18796) (xy 0.1651 -0.19558) (xy 0.1651 -0.7366) (xy 0.16256 -0.76835) (xy 0.1524 -0.8001)
						(xy 0.13716 -0.82804) (xy 0.11684 -0.85344) (xy 0.09144 -0.87376) (xy 0.0635 -0.889) (xy 0.03175 -0.89916)
					)
					(width 0)
					(fill yes)
				)
			)
		)
		(pad "180" smd custom
			(at 24.45004 4.100068 180)
			(size 0.1143 0.1143)
			(layers "B.Cu" "B.Mask" "B.Paste")
			(net "M_B_DQ60")
			(options
				(clearance outline)
				(anchor circle)
			)
			(primitives
				(gr_poly
					(pts
						(xy 0 -0.9017) (xy -0.03175 -0.89916) (xy -0.0635 -0.889) (xy -0.09144 -0.87376) (xy -0.11684 -0.85344)
						(xy -0.13716 -0.82804) (xy -0.1524 -0.8001) (xy -0.16256 -0.76835) (xy -0.1651 -0.7366) (xy -0.1651 -0.11938)
						(xy -0.17272 -0.11176) (xy -0.19812 -0.0762) (xy -0.2032 -0.06604) (xy -0.20701 -0.05715) (xy -0.21209 -0.04699)
						(xy -0.2159 -0.03683) (xy -0.21844 -0.02667) (xy -0.22225 -0.01524) (xy -0.22352 -0.00508) (xy -0.22606 0.00508)
						(xy -0.22733 0.01651) (xy -0.22733 0.02667) (xy -0.2286 0.0381) (xy -0.22733 0.04953) (xy -0.22733 0.05969)
						(xy -0.22606 0.07112) (xy -0.22352 0.08128) (xy -0.22225 0.09144) (xy -0.21844 0.10287) (xy -0.2159 0.11303)
						(xy -0.21209 0.12319) (xy -0.20701 0.13335) (xy -0.2032 0.14224) (xy -0.19812 0.1524) (xy -0.17272 0.18796)
						(xy -0.1651 0.19558) (xy -0.1651 0.7366) (xy -0.16256 0.76835) (xy -0.1524 0.8001) (xy -0.13716 0.82804)
						(xy -0.11684 0.85344) (xy -0.09144 0.87376) (xy -0.0635 0.889) (xy -0.03175 0.89916) (xy 0 0.9017)
						(xy 0.03175 0.89916) (xy 0.0635 0.889) (xy 0.09144 0.87376) (xy 0.11684 0.85344) (xy 0.13716 0.82804)
						(xy 0.1524 0.8001) (xy 0.16256 0.76835) (xy 0.1651 0.7366) (xy 0.1651 0.19685) (xy 0.17272 0.18923)
						(xy 0.17907 0.18034) (xy 0.18669 0.17145) (xy 0.19177 0.16256) (xy 0.19812 0.15367) (xy 0.20828 0.13335)
						(xy 0.21971 0.10287) (xy 0.22225 0.09271) (xy 0.22479 0.08128) (xy 0.22606 0.07112) (xy 0.2286 0.05969)
						(xy 0.2286 0.01651) (xy 0.22606 0.00508) (xy 0.22479 -0.00508) (xy 0.22225 -0.01651) (xy 0.21971 -0.02667)
						(xy 0.20828 -0.05715) (xy 0.19812 -0.07747) (xy 0.19177 -0.08636) (xy 0.18669 -0.09525) (xy 0.17907 -0.10414)
						(xy 0.17272 -0.11303) (xy 0.1651 -0.12065) (xy 0.1651 -0.7366) (xy 0.16256 -0.76835) (xy 0.1524 -0.8001)
						(xy 0.13716 -0.82804) (xy 0.11684 -0.85344) (xy 0.09144 -0.87376) (xy 0.0635 -0.889) (xy 0.03175 -0.89916)
					)
					(width 0)
					(fill yes)
				)
			)
		)
		(pad "181" smd custom
			(at 24.750014 -4.100068 180)
			(size 0.1143 0.1143)
			(layers "B.Cu" "B.Mask" "B.Paste")
			(net "GND")
			(options
				(clearance outline)
				(anchor circle)
			)
			(primitives
				(gr_poly
					(pts
						(xy 0 -0.9017) (xy -0.03175 -0.89916) (xy -0.0635 -0.889) (xy -0.09144 -0.87376) (xy -0.11684 -0.85344)
						(xy -0.13716 -0.82804) (xy -0.1524 -0.8001) (xy -0.16256 -0.76835) (xy -0.1651 -0.7366) (xy -0.1651 -0.44958)
						(xy -0.17272 -0.44196) (xy -0.19812 -0.4064) (xy -0.2032 -0.39624) (xy -0.20701 -0.38735) (xy -0.21209 -0.37719)
						(xy -0.2159 -0.36703) (xy -0.21844 -0.35687) (xy -0.22225 -0.34544) (xy -0.22352 -0.33528) (xy -0.22606 -0.32512)
						(xy -0.22733 -0.31369) (xy -0.22733 -0.30353) (xy -0.2286 -0.2921) (xy -0.22733 -0.28067) (xy -0.22733 -0.27051)
						(xy -0.22606 -0.25908) (xy -0.22352 -0.24892) (xy -0.22225 -0.23876) (xy -0.21844 -0.22733) (xy -0.2159 -0.21717)
						(xy -0.21209 -0.20701) (xy -0.20701 -0.19685) (xy -0.2032 -0.18796) (xy -0.19812 -0.1778) (xy -0.17272 -0.14224)
						(xy -0.1651 -0.13462) (xy -0.1651 0.7366) (xy -0.16256 0.76835) (xy -0.1524 0.8001) (xy -0.13716 0.82804)
						(xy -0.11684 0.85344) (xy -0.09144 0.87376) (xy -0.0635 0.889) (xy -0.03175 0.89916) (xy 0 0.9017)
						(xy 0.03175 0.89916) (xy 0.0635 0.889) (xy 0.09144 0.87376) (xy 0.11684 0.85344) (xy 0.13716 0.82804)
						(xy 0.1524 0.8001) (xy 0.16256 0.76835) (xy 0.1651 0.7366) (xy 0.1651 -0.13462) (xy 0.17272 -0.14224)
						(xy 0.19812 -0.1778) (xy 0.2032 -0.18796) (xy 0.20701 -0.19685) (xy 0.21209 -0.20701) (xy 0.2159 -0.21717)
						(xy 0.21844 -0.22733) (xy 0.22225 -0.23876) (xy 0.22352 -0.24892) (xy 0.22606 -0.25908) (xy 0.22733 -0.27051)
						(xy 0.22733 -0.28067) (xy 0.2286 -0.2921) (xy 0.22733 -0.30353) (xy 0.22733 -0.31369) (xy 0.22606 -0.32512)
						(xy 0.22352 -0.33528) (xy 0.22225 -0.34544) (xy 0.21844 -0.35687) (xy 0.2159 -0.36703) (xy 0.21209 -0.37719)
						(xy 0.20701 -0.38735) (xy 0.2032 -0.39624) (xy 0.19812 -0.4064) (xy 0.17272 -0.44196) (xy 0.1651 -0.44958)
						(xy 0.1651 -0.7366) (xy 0.16256 -0.76835) (xy 0.1524 -0.8001) (xy 0.13716 -0.82804) (xy 0.11684 -0.85344)
						(xy 0.09144 -0.87376) (xy 0.0635 -0.889) (xy 0.03175 -0.89916)
					)
					(width 0)
					(fill yes)
				)
			)
		)
	)
)
